(kicad_pcb
	(version 20260206)
	(generator "pcbnew")
	(generator_version "10.0")
	(general
		(thickness 1.6)
		(legacy_teardrops no)
	)
	(paper "A4")
	(title_block
		(title "01162023_DA0F0TEBIF0_F0T_Expander_BD_F_brd_V02_OCP.brd")
		(comment 1 "Grand Teton / footprints 2085-2090 of 9728")
	)
	(layers
		(0 "F.Cu" signal "TOP")
		(4 "In1.Cu" signal "GND")
		(6 "In2.Cu" signal "VCC")
		(8 "In3.Cu" signal "VCC1")
		(10 "In4.Cu" signal "GND1")
		(12 "In5.Cu" signal "IN1")
		(14 "In6.Cu" signal "GND2")
		(16 "In7.Cu" signal "IN2")
		(18 "In8.Cu" signal "GND3")
		(20 "In9.Cu" signal "IN3")
		(22 "In10.Cu" signal "GND4")
		(24 "In11.Cu" signal "IN4")
		(26 "In12.Cu" signal "GND5")
		(28 "In13.Cu" signal "IN5")
		(30 "In14.Cu" signal "GND6")
		(32 "In15.Cu" signal "IN6")
		(34 "In16.Cu" signal "GND7")
		(2 "B.Cu" signal "BOTTOM")
		(9 "F.Adhes" user "F.Adhesive")
		(11 "B.Adhes" user "B.Adhesive")
		(13 "F.Paste" user "Package Geometry/Pastemask Top")
		(15 "B.Paste" user "Package Geometry/Pastemask Bottom")
		(5 "F.SilkS" user "Ref Des/Silkscreen Top")
		(7 "B.SilkS" user "Ref Des/Silkscreen Bottom")
		(1 "F.Mask" user "Board Geometry/Soldermask Top")
		(3 "B.Mask" user "Board Geometry/Soldermask Bottom")
		(17 "Dwgs.User" user "User.Drawings")
		(19 "Cmts.User" user "User.Comments")
		(21 "Eco1.User" user "User.Eco1")
		(23 "Eco2.User" user "User.Eco2")
		(25 "Edge.Cuts" user "Board Geometry/Outline")
		(27 "Margin" user)
		(31 "F.CrtYd" user "Package Geometry/Place Bound Top")
		(29 "B.CrtYd" user "Package Geometry/Place Bound Bottom")
		(35 "F.Fab" user "Ref Des/Assembly Top")
		(33 "B.Fab" user "Ref Des/Assembly Bottom")
	)
	(footprint ""
		(layer "F.Cu")
		(at 262.915146 -59.546236 90)
		(property "Reference" "C2895"
			(at 0 0 90)
			(layer "F.SilkS")
			(hide yes)
			(effects
				(font
					(size 1.27 1.27)
				)
			)
		)
		(property "Value" ""
			(at 0 0 90)
			(layer "F.Fab")
			(effects
				(font
					(size 1.27 1.27)
				)
			)
		)
		(duplicate_pad_numbers_are_jumpers no)
		(fp_line
			(start 0.7874 -0.4064)
			(end 0.7874 0.4064)
			(stroke
				(width 0.1524)
				(type default)
			)
			(layer "F.SilkS")
		)
		(fp_line
			(start -0.7874 -0.4064)
			(end 0.7874 -0.4064)
			(stroke
				(width 0.1524)
				(type default)
			)
			(layer "F.SilkS")
		)
		(fp_line
			(start 0.7874 0.4064)
			(end -0.7874 0.4064)
			(stroke
				(width 0.1524)
				(type default)
			)
			(layer "F.SilkS")
		)
		(fp_line
			(start -0.7874 0.4064)
			(end -0.7874 -0.4064)
			(stroke
				(width 0.1524)
				(type default)
			)
			(layer "F.SilkS")
		)
		(fp_line
			(start -0.12065 -0.305054)
			(end -0.12065 -0.2794)
			(stroke
				(width 0.1)
				(type default)
			)
			(layer "F.Fab")
		)
		(fp_line
			(start -0.67945 -0.305054)
			(end -0.12065 -0.305054)
			(stroke
				(width 0.1)
				(type default)
			)
			(layer "F.Fab")
		)
		(fp_line
			(start 0.67945 -0.3048)
			(end 0.67945 0.3048)
			(stroke
				(width 0.1)
				(type default)
			)
			(layer "F.Fab")
		)
		(fp_line
			(start 0.12065 -0.3048)
			(end 0.67945 -0.3048)
			(stroke
				(width 0.1)
				(type default)
			)
			(layer "F.Fab")
		)
		(fp_line
			(start 0.12065 -0.2794)
			(end 0.12065 -0.3048)
			(stroke
				(width 0.1)
				(type default)
			)
			(layer "F.Fab")
		)
		(fp_line
			(start -0.12065 -0.2794)
			(end 0.12065 -0.2794)
			(stroke
				(width 0.1)
				(type default)
			)
			(layer "F.Fab")
		)
		(fp_line
			(start 0.120396 0.2794)
			(end -0.12065 0.2794)
			(stroke
				(width 0.1)
				(type default)
			)
			(layer "F.Fab")
		)
		(fp_line
			(start -0.12065 0.2794)
			(end -0.12065 0.3048)
			(stroke
				(width 0.1)
				(type default)
			)
			(layer "F.Fab")
		)
		(fp_line
			(start 0.67945 0.3048)
			(end 0.120396 0.3048)
			(stroke
				(width 0.1)
				(type default)
			)
			(layer "F.Fab")
		)
		(fp_line
			(start 0.120396 0.3048)
			(end 0.120396 0.2794)
			(stroke
				(width 0.1)
				(type default)
			)
			(layer "F.Fab")
		)
		(fp_line
			(start -0.12065 0.3048)
			(end -0.67945 0.3048)
			(stroke
				(width 0.1)
				(type default)
			)
			(layer "F.Fab")
		)
		(fp_line
			(start -0.67945 0.3048)
			(end -0.67945 -0.305054)
			(stroke
				(width 0.1)
				(type default)
			)
			(layer "F.Fab")
		)
		(pad "1" smd circle
			(at -0.40005 0 90)
			(size 0 0)
			(layers "F.Cu" "F.Mask" "F.Paste")
			(net "SSD9_AUX_P3V3_EN_R")
		)
		(pad "2" smd circle
			(at 0.40005 0 90)
			(size 0 0)
			(layers "F.Cu" "F.Mask" "F.Paste")
			(net "GND")
		)
	)
	(footprint ""
		(layer "F.Cu")
		(at 12.960096 -174.872142)
		(property "Reference" "PC22"
			(at 0 0 0)
			(layer "F.SilkS")
			(hide yes)
			(effects
				(font
					(size 1.27 1.27)
				)
			)
		)
		(property "Value" ""
			(at 0 0 0)
			(layer "F.Fab")
			(effects
				(font
					(size 1.27 1.27)
				)
			)
		)
		(duplicate_pad_numbers_are_jumpers no)
		(fp_line
			(start -0.7874 -0.4064)
			(end 0.7874 -0.4064)
			(stroke
				(width 0.1524)
				(type default)
			)
			(layer "F.SilkS")
		)
		(fp_line
			(start -0.7874 0.4064)
			(end -0.7874 -0.4064)
			(stroke
				(width 0.1524)
				(type default)
			)
			(layer "F.SilkS")
		)
		(fp_line
			(start 0.7874 -0.4064)
			(end 0.7874 0.4064)
			(stroke
				(width 0.1524)
				(type default)
			)
			(layer "F.SilkS")
		)
		(fp_line
			(start 0.7874 0.4064)
			(end -0.7874 0.4064)
			(stroke
				(width 0.1524)
				(type default)
			)
			(layer "F.SilkS")
		)
		(fp_line
			(start -0.67945 -0.305054)
			(end -0.12065 -0.305054)
			(stroke
				(width 0.1)
				(type default)
			)
			(layer "F.Fab")
		)
		(fp_line
			(start -0.67945 0.3048)
			(end -0.67945 -0.305054)
			(stroke
				(width 0.1)
				(type default)
			)
			(layer "F.Fab")
		)
		(fp_line
			(start -0.12065 -0.305054)
			(end -0.12065 -0.2794)
			(stroke
				(width 0.1)
				(type default)
			)
			(layer "F.Fab")
		)
		(fp_line
			(start -0.12065 -0.2794)
			(end 0.12065 -0.2794)
			(stroke
				(width 0.1)
				(type default)
			)
			(layer "F.Fab")
		)
		(fp_line
			(start -0.12065 0.2794)
			(end -0.12065 0.3048)
			(stroke
				(width 0.1)
				(type default)
			)
			(layer "F.Fab")
		)
		(fp_line
			(start -0.12065 0.3048)
			(end -0.67945 0.3048)
			(stroke
				(width 0.1)
				(type default)
			)
			(layer "F.Fab")
		)
		(fp_line
			(start 0.120396 0.2794)
			(end -0.12065 0.2794)
			(stroke
				(width 0.1)
				(type default)
			)
			(layer "F.Fab")
		)
		(fp_line
			(start 0.120396 0.3048)
			(end 0.120396 0.2794)
			(stroke
				(width 0.1)
				(type default)
			)
			(layer "F.Fab")
		)
		(fp_line
			(start 0.12065 -0.3048)
			(end 0.67945 -0.3048)
			(stroke
				(width 0.1)
				(type default)
			)
			(layer "F.Fab")
		)
		(fp_line
			(start 0.12065 -0.2794)
			(end 0.12065 -0.3048)
			(stroke
				(width 0.1)
				(type default)
			)
			(layer "F.Fab")
		)
		(fp_line
			(start 0.67945 -0.3048)
			(end 0.67945 0.3048)
			(stroke
				(width 0.1)
				(type default)
			)
			(layer "F.Fab")
		)
		(fp_line
			(start 0.67945 0.3048)
			(end 0.120396 0.3048)
			(stroke
				(width 0.1)
				(type default)
			)
			(layer "F.Fab")
		)
		(pad "1" smd circle
			(at -0.40005 0)
			(size 0 0)
			(layers "F.Cu" "F.Mask" "F.Paste")
			(net "P5V_AUX")
		)
		(pad "2" smd circle
			(at 0.40005 0)
			(size 0 0)
			(layers "F.Cu" "F.Mask" "F.Paste")
			(net "GND")
		)
	)
	(footprint ""
		(layer "F.Cu")
		(at 252.687582 -25.342342 -90)
		(property "Reference" "R434"
			(at 0 0 270)
			(layer "F.SilkS")
			(hide yes)
			(effects
				(font
					(size 1.27 1.27)
				)
			)
		)
		(property "Value" ""
			(at 0 0 270)
			(layer "F.Fab")
			(effects
				(font
					(size 1.27 1.27)
				)
			)
		)
		(duplicate_pad_numbers_are_jumpers no)
		(fp_line
			(start -0.7874 0.4064)
			(end -0.7874 -0.4064)
			(stroke
				(width 0.1524)
				(type default)
			)
			(layer "F.SilkS")
		)
		(fp_line
			(start 0.7874 0.4064)
			(end -0.7874 0.4064)
			(stroke
				(width 0.1524)
				(type default)
			)
			(layer "F.SilkS")
		)
		(fp_line
			(start -0.7874 -0.4064)
			(end 0.7874 -0.4064)
			(stroke
				(width 0.1524)
				(type default)
			)
			(layer "F.SilkS")
		)
		(fp_line
			(start 0.7874 -0.4064)
			(end 0.7874 0.4064)
			(stroke
				(width 0.1524)
				(type default)
			)
			(layer "F.SilkS")
		)
		(fp_line
			(start -0.67945 0.3048)
			(end -0.67945 -0.305054)
			(stroke
				(width 0.1)
				(type default)
			)
			(layer "F.Fab")
		)
		(fp_line
			(start -0.12065 0.3048)
			(end -0.67945 0.3048)
			(stroke
				(width 0.1)
				(type default)
			)
			(layer "F.Fab")
		)
		(fp_line
			(start 0.120396 0.3048)
			(end 0.120396 0.2794)
			(stroke
				(width 0.1)
				(type default)
			)
			(layer "F.Fab")
		)
		(fp_line
			(start 0.67945 0.3048)
			(end 0.120396 0.3048)
			(stroke
				(width 0.1)
				(type default)
			)
			(layer "F.Fab")
		)
		(fp_line
			(start -0.12065 0.2794)
			(end -0.12065 0.3048)
			(stroke
				(width 0.1)
				(type default)
			)
			(layer "F.Fab")
		)
		(fp_line
			(start 0.120396 0.2794)
			(end -0.12065 0.2794)
			(stroke
				(width 0.1)
				(type default)
			)
			(layer "F.Fab")
		)
		(fp_line
			(start -0.12065 -0.2794)
			(end 0.12065 -0.2794)
			(stroke
				(width 0.1)
				(type default)
			)
			(layer "F.Fab")
		)
		(fp_line
			(start 0.12065 -0.2794)
			(end 0.12065 -0.3048)
			(stroke
				(width 0.1)
				(type default)
			)
			(layer "F.Fab")
		)
		(fp_line
			(start 0.12065 -0.3048)
			(end 0.67945 -0.3048)
			(stroke
				(width 0.1)
				(type default)
			)
			(layer "F.Fab")
		)
		(fp_line
			(start 0.67945 -0.3048)
			(end 0.67945 0.3048)
			(stroke
				(width 0.1)
				(type default)
			)
			(layer "F.Fab")
		)
		(fp_line
			(start -0.67945 -0.305054)
			(end -0.12065 -0.305054)
			(stroke
				(width 0.1)
				(type default)
			)
			(layer "F.Fab")
		)
		(fp_line
			(start -0.12065 -0.305054)
			(end -0.12065 -0.2794)
			(stroke
				(width 0.1)
				(type default)
			)
			(layer "F.Fab")
		)
		(pad "1" smd circle
			(at -0.40005 0 270)
			(size 0 0)
			(layers "F.Cu" "F.Mask" "F.Paste")
			(net "GND")
		)
		(pad "2" smd circle
			(at 0.40005 0 270)
			(size 0 0)
			(layers "F.Cu" "F.Mask" "F.Paste")
			(net "DUALPORT_N_SSD8")
		)
	)
	(footprint ""
		(layer "F.Cu")
		(at 154.699716 -151.279352 180)
		(property "Reference" "R118"
			(at 0 0 180)
			(layer "F.SilkS")
			(hide yes)
			(effects
				(font
					(size 1.27 1.27)
				)
			)
		)
		(property "Value" ""
			(at 0 0 180)
			(layer "F.Fab")
			(effects
				(font
					(size 1.27 1.27)
				)
			)
		)
		(duplicate_pad_numbers_are_jumpers no)
		(fp_line
			(start 0.7874 0.4064)
			(end -0.7874 0.4064)
			(stroke
				(width 0.1524)
				(type default)
			)
			(layer "F.SilkS")
		)
		(fp_line
			(start 0.7874 -0.4064)
			(end 0.7874 0.4064)
			(stroke
				(width 0.1524)
				(type default)
			)
			(layer "F.SilkS")
		)
		(fp_line
			(start -0.7874 0.4064)
			(end -0.7874 -0.4064)
			(stroke
				(width 0.1524)
				(type default)
			)
			(layer "F.SilkS")
		)
		(fp_line
			(start -0.7874 -0.4064)
			(end 0.7874 -0.4064)
			(stroke
				(width 0.1524)
				(type default)
			)
			(layer "F.SilkS")
		)
		(fp_line
			(start 0.67945 0.3048)
			(end 0.120396 0.3048)
			(stroke
				(width 0.1)
				(type default)
			)
			(layer "F.Fab")
		)
		(fp_line
			(start 0.67945 -0.3048)
			(end 0.67945 0.3048)
			(stroke
				(width 0.1)
				(type default)
			)
			(layer "F.Fab")
		)
		(fp_line
			(start 0.12065 -0.2794)
			(end 0.12065 -0.3048)
			(stroke
				(width 0.1)
				(type default)
			)
			(layer "F.Fab")
		)
		(fp_line
			(start 0.12065 -0.3048)
			(end 0.67945 -0.3048)
			(stroke
				(width 0.1)
				(type default)
			)
			(layer "F.Fab")
		)
		(fp_line
			(start 0.120396 0.3048)
			(end 0.120396 0.2794)
			(stroke
				(width 0.1)
				(type default)
			)
			(layer "F.Fab")
		)
		(fp_line
			(start 0.120396 0.2794)
			(end -0.12065 0.2794)
			(stroke
				(width 0.1)
				(type default)
			)
			(layer "F.Fab")
		)
		(fp_line
			(start -0.12065 0.3048)
			(end -0.67945 0.3048)
			(stroke
				(width 0.1)
				(type default)
			)
			(layer "F.Fab")
		)
		(fp_line
			(start -0.12065 0.2794)
			(end -0.12065 0.3048)
			(stroke
				(width 0.1)
				(type default)
			)
			(layer "F.Fab")
		)
		(fp_line
			(start -0.12065 -0.2794)
			(end 0.12065 -0.2794)
			(stroke
				(width 0.1)
				(type default)
			)
			(layer "F.Fab")
		)
		(fp_line
			(start -0.12065 -0.305054)
			(end -0.12065 -0.2794)
			(stroke
				(width 0.1)
				(type default)
			)
			(layer "F.Fab")
		)
		(fp_line
			(start -0.67945 0.3048)
			(end -0.67945 -0.305054)
			(stroke
				(width 0.1)
				(type default)
			)
			(layer "F.Fab")
		)
		(fp_line
			(start -0.67945 -0.305054)
			(end -0.12065 -0.305054)
			(stroke
				(width 0.1)
				(type default)
			)
			(layer "F.Fab")
		)
		(pad "1" smd circle
			(at -0.40005 0 180)
			(size 0 0)
			(layers "F.Cu" "F.Mask" "F.Paste")
			(net "NCSI_NIC2_RXD0")
		)
		(pad "2" smd circle
			(at 0.40005 0 180)
			(size 0 0)
			(layers "F.Cu" "F.Mask" "F.Paste")
			(net "GND")
		)
	)
	(footprint ""
		(layer "F.Cu")
		(at 73.885552 -25.1587 -90)
		(property "Reference" "R5736"
			(at 0 0 270)
			(layer "F.SilkS")
			(hide yes)
			(effects
				(font
					(size 1.27 1.27)
				)
			)
		)
		(property "Value" ""
			(at 0 0 270)
			(layer "F.Fab")
			(effects
				(font
					(size 1.27 1.27)
				)
			)
		)
		(duplicate_pad_numbers_are_jumpers no)
		(fp_line
			(start -0.7874 0.4064)
			(end -0.7874 -0.4064)
			(stroke
				(width 0.1524)
				(type default)
			)
			(layer "F.SilkS")
		)
		(fp_line
			(start 0.7874 0.4064)
			(end -0.7874 0.4064)
			(stroke
				(width 0.1524)
				(type default)
			)
			(layer "F.SilkS")
		)
		(fp_line
			(start -0.7874 -0.4064)
			(end 0.7874 -0.4064)
			(stroke
				(width 0.1524)
				(type default)
			)
			(layer "F.SilkS")
		)
		(fp_line
			(start 0.7874 -0.4064)
			(end 0.7874 0.4064)
			(stroke
				(width 0.1524)
				(type default)
			)
			(layer "F.SilkS")
		)
		(fp_line
			(start -0.67945 0.3048)
			(end -0.67945 -0.305054)
			(stroke
				(width 0.1)
				(type default)
			)
			(layer "F.Fab")
		)
		(fp_line
			(start -0.12065 0.3048)
			(end -0.67945 0.3048)
			(stroke
				(width 0.1)
				(type default)
			)
			(layer "F.Fab")
		)
		(fp_line
			(start 0.120396 0.3048)
			(end 0.120396 0.2794)
			(stroke
				(width 0.1)
				(type default)
			)
			(layer "F.Fab")
		)
		(fp_line
			(start 0.67945 0.3048)
			(end 0.120396 0.3048)
			(stroke
				(width 0.1)
				(type default)
			)
			(layer "F.Fab")
		)
		(fp_line
			(start -0.12065 0.2794)
			(end -0.12065 0.3048)
			(stroke
				(width 0.1)
				(type default)
			)
			(layer "F.Fab")
		)
		(fp_line
			(start 0.120396 0.2794)
			(end -0.12065 0.2794)
			(stroke
				(width 0.1)
				(type default)
			)
			(layer "F.Fab")
		)
		(fp_line
			(start -0.12065 -0.2794)
			(end 0.12065 -0.2794)
			(stroke
				(width 0.1)
				(type default)
			)
			(layer "F.Fab")
		)
		(fp_line
			(start 0.12065 -0.2794)
			(end 0.12065 -0.3048)
			(stroke
				(width 0.1)
				(type default)
			)
			(layer "F.Fab")
		)
		(fp_line
			(start 0.12065 -0.3048)
			(end 0.67945 -0.3048)
			(stroke
				(width 0.1)
				(type default)
			)
			(layer "F.Fab")
		)
		(fp_line
			(start 0.67945 -0.3048)
			(end 0.67945 0.3048)
			(stroke
				(width 0.1)
				(type default)
			)
			(layer "F.Fab")
		)
		(fp_line
			(start -0.67945 -0.305054)
			(end -0.12065 -0.305054)
			(stroke
				(width 0.1)
				(type default)
			)
			(layer "F.Fab")
		)
		(fp_line
			(start -0.12065 -0.305054)
			(end -0.12065 -0.2794)
			(stroke
				(width 0.1)
				(type default)
			)
			(layer "F.Fab")
		)
		(pad "1" smd circle
			(at -0.40005 0 270)
			(size 0 0)
			(layers "F.Cu" "F.Mask" "F.Paste")
			(net "SSD2_LED_ISO_N")
		)
		(pad "2" smd circle
			(at 0.40005 0 270)
			(size 0 0)
			(layers "F.Cu" "F.Mask" "F.Paste")
			(net "SSD2_LED_ISO_R_N")
		)
	)
	(footprint ""
		(layer "F.Cu")
		(at 140.582142 -37.025072)
		(property "Reference" "R5665"
			(at 0 0 0)
			(layer "F.SilkS")
			(hide yes)
			(effects
				(font
					(size 1.27 1.27)
				)
			)
		)
		(property "Value" ""
			(at 0 0 0)
			(layer "F.Fab")
			(effects
				(font
					(size 1.27 1.27)
				)
			)
		)
		(duplicate_pad_numbers_are_jumpers no)
		(fp_line
			(start -0.7874 -0.4064)
			(end 0.7874 -0.4064)
			(stroke
				(width 0.1524)
				(type default)
			)
			(layer "F.SilkS")
		)
		(fp_line
			(start -0.7874 0.4064)
			(end -0.7874 -0.4064)
			(stroke
				(width 0.1524)
				(type default)
			)
			(layer "F.SilkS")
		)
		(fp_line
			(start 0.7874 -0.4064)
			(end 0.7874 0.4064)
			(stroke
				(width 0.1524)
				(type default)
			)
			(layer "F.SilkS")
		)
		(fp_line
			(start 0.7874 0.4064)
			(end -0.7874 0.4064)
			(stroke
				(width 0.1524)
				(type default)
			)
			(layer "F.SilkS")
		)
		(fp_line
			(start -0.67945 -0.305054)
			(end -0.12065 -0.305054)
			(stroke
				(width 0.1)
				(type default)
			)
			(layer "F.Fab")
		)
		(fp_line
			(start -0.67945 0.3048)
			(end -0.67945 -0.305054)
			(stroke
				(width 0.1)
				(type default)
			)
			(layer "F.Fab")
		)
		(fp_line
			(start -0.12065 -0.305054)
			(end -0.12065 -0.2794)
			(stroke
				(width 0.1)
				(type default)
			)
			(layer "F.Fab")
		)
		(fp_line
			(start -0.12065 -0.2794)
			(end 0.12065 -0.2794)
			(stroke
				(width 0.1)
				(type default)
			)
			(layer "F.Fab")
		)
		(fp_line
			(start -0.12065 0.2794)
			(end -0.12065 0.3048)
			(stroke
				(width 0.1)
				(type default)
			)
			(layer "F.Fab")
		)
		(fp_line
			(start -0.12065 0.3048)
			(end -0.67945 0.3048)
			(stroke
				(width 0.1)
				(type default)
			)
			(layer "F.Fab")
		)
		(fp_line
			(start 0.120396 0.2794)
			(end -0.12065 0.2794)
			(stroke
				(width 0.1)
				(type default)
			)
			(layer "F.Fab")
		)
		(fp_line
			(start 0.120396 0.3048)
			(end 0.120396 0.2794)
			(stroke
				(width 0.1)
				(type default)
			)
			(layer "F.Fab")
		)
		(fp_line
			(start 0.12065 -0.3048)
			(end 0.67945 -0.3048)
			(stroke
				(width 0.1)
				(type default)
			)
			(layer "F.Fab")
		)
		(fp_line
			(start 0.12065 -0.2794)
			(end 0.12065 -0.3048)
			(stroke
				(width 0.1)
				(type default)
			)
			(layer "F.Fab")
		)
		(fp_line
			(start 0.67945 -0.3048)
			(end 0.67945 0.3048)
			(stroke
				(width 0.1)
				(type default)
			)
			(layer "F.Fab")
		)
		(fp_line
			(start 0.67945 0.3048)
			(end 0.120396 0.3048)
			(stroke
				(width 0.1)
				(type default)
			)
			(layer "F.Fab")
		)
		(pad "1" smd circle
			(at -0.40005 0)
			(size 0 0)
			(layers "F.Cu" "F.Mask" "F.Paste")
			(net "RST_SMB_SSD_R_N")
		)
		(pad "2" smd circle
			(at 0.40005 0)
			(size 0 0)
			(layers "F.Cu" "F.Mask" "F.Paste")
			(net "RST_SMB_SSD5_N")
		)
	)
)
